FILE_TYPE = CONNECTIVITY;
{Allegro Design Entry HDL 17.2-2016 S081 (4005846) 1/11/2022}
"PAGE_NUMBER" = 138;
0"NC";
1"GND\g";
2"GND\g";
3"GND\g";
4"GND\g";
5"GND\g";
6"GND\g";
7"GND\g";
8"GND\g";
9"SMB_APML_CPU0_R_SDA";
10"SMB_APML_CPU0_SCL";
11"SMB_CPU0_SEC_SDA";
12"SMB_APML_CPU1_SCL";
13"SMB_CPU1_SEC_SCL";
14"SMB_CPU1_SEC_SDA";
15"SMB_APML_CPU0_SCL";
16"SMB_CPU0_SEC_SCL";
17"SMB_CPU0_SEC_SDA";
18"PVDD11_S3_P1\g";
19"SMB_APML_CPU1_R_SDA";
20"SMB_SCM_11_XLTR_SDA";
21"SMB_SCM_11_XLTR_SCL";
22"SMB_SCM_10_XLTR_SCL";
23"SMB_CPU0_SEC_R_SDA";
24"SMB_CPU0_SEC_R_SCL";
25"I3C_MUX_CPU1_VIO";
26"PVDD18_S5_P0\g";
27"PVDD18_S5_P0\g";
28"PVDD11_S3_P0\g";
29"SMB_APML_CPU1_SDA";
30"SMB_SCM_10_XLTR_SDA";
31"I3C_MUX_CPU0_VIO";
32"SMB_APML_CPU0_R_SCL";
33"SMB_CPU1_SEC_R_SCL";
34"SMB_CPU1_SEC_R_SDA";
35"SMB_APML_CPU1_SCL";
36"SMB_APML_CPU1_R_SCL";
37"SMB_APML_CPU1_SDA";
38"SMB_APML_CPU0_SDA";
39"SMB_CPU1_SEC_SDA";
40"SMB_CPU1_SEC_SCL";
41"SMB_CPU0_SEC_SCL";
42"SMB_APML_CPU0_SDA";
%"Q_RES"
"1","(2025,5400)","0","pure_quanta","I10";
;
LOCATION"R142"
$SEC"1"
CDS_SEC"1"
MATERIAL"EMPTY"
VALUE"0"
CDS_LIB"pure_quanta"
WATTAGE"1/16W"
TOLERANCE"5%"
PART_NUMBER"CS00002JB38"
PACK_TYPE"0402LF";
"B"
$PN"2"32;
"A"
$PN"1"22;
%"Q_RES"
"1","(2025,5325)","0","pure_quanta","I11";
;
LOCATION"R143"
$SEC"1"
CDS_SEC"1"
MATERIAL"EMPTY"
VALUE"0"
CDS_LIB"pure_quanta"
WATTAGE"1/16W"
TOLERANCE"5%"
PART_NUMBER"CS00002JB38"
PACK_TYPE"0402LF";
"B"
$PN"2"9;
"A"
$PN"1"30;
%"P1V0"
"1","(1250,5100)","0","pure_quanta_power","I12";
;
HDL_POWER"PVDD18_S5_P0"
CDS_LIB"pure_quanta_power";
"A"26;
%"IML3112Y2B000NCG8"
"1","(2050,4325)","0","pure_quanta","I13";
;
LOCATION"U213"
$SEC"1"
CDS_SEC"1"
PART_TYPE"SMLF"
MATERIAL"IC"
VALUE"IML3112-Y2B000NCG8"
PART_NUMBER"AL003112004"
CDS_LIB"pure_quanta"
NEEDS_NO_SIZE"TRUE"
CDS_LMAN_SYM_OUTLINE"-275,250,275,-250";
"TH_GND"
$PN"9"8;
"LSDA_1||HSA"
$PN"8"23;
"HSCL"
$PN"3"22;
"LSCL_0"
$PN"4"32;
"LSDA_0"
$PN"1"9;
"VIO"
$PN"7"31;
"LSCL_1"
$PN"6"24;
"VDD"
$PN"5"26;
"HSDA"
$PN"2"30;
%"Q_RES"
"1","(800,4925)","0","pure_quanta","I14";
;
LOCATION"R139"
$SEC"1"
CDS_SEC"1"
MATERIAL"EMPTY"
VALUE"0"
CDS_LIB"pure_quanta"
WATTAGE"1/16W"
TOLERANCE"5%"
PART_NUMBER"CS00002JB38"
PACK_TYPE"0402LF";
"B"
$PN"2"26;
"A"
$PN"1"31;
%"Q_CAP"
"1","(1075,4750)","0","pure_quanta","I15";
;
LOCATION"C24"
$SEC"1"
CDS_SEC"1"
MATERIAL"X6S"
TOLERANCE"20%"
VALUE"10UF"
VOLTAGE"6.3V"
PACK_TYPE"C0402"
CDS_LIB"pure_quanta"
PART_NUMBER"CH6101MEB01";
"B"
$PN"2"1;
"A"
$PN"1"26;
%"UNIVERSAL_GND"
"1","(1075,4550)","0","pure_quanta_power","I16";
;
CDS_LIB"pure_quanta_power"
HDL_POWER"GND";
"A"1;
%"Q_CAP"
"1","(550,4750)","0","pure_quanta","I17";
;
LOCATION"C9"
$SEC"1"
CDS_SEC"1"
MATERIAL"X6S"
TOLERANCE"10%"
VALUE"1UF"
VOLTAGE"25V"
PACK_TYPE"C0402"
CDS_LIB"pure_quanta"
PART_NUMBER"CH5104KEB02";
"B"
$PN"2"2;
"A"
$PN"1"31;
%"UNIVERSAL_GND"
"1","(550,4550)","0","pure_quanta_power","I18";
;
CDS_LIB"pure_quanta_power"
HDL_POWER"GND";
"A"2;
%"Q_RES"
"1","(3550,2250)","0","pure_quanta","I25";
;
LOCATION"R1160"
$SEC"1"
CDS_SEC"1"
VALUE"0"
CDS_LIB"pure_quanta"
WATTAGE"1/16W"
MATERIAL"CHIP"
TOLERANCE"5%"
PART_NUMBER"CS00002JB38"
PACK_TYPE"0402LF";
"B"
$PN"2"35;
"A"
$PN"1"36;
%"Q_RES"
"1","(3550,2300)","0","pure_quanta","I26";
;
LOCATION"R1159"
$SEC"1"
CDS_SEC"1"
VALUE"0"
CDS_LIB"pure_quanta"
WATTAGE"1/16W"
MATERIAL"CHIP"
TOLERANCE"5%"
PART_NUMBER"CS00002JB38"
PACK_TYPE"0402LF";
"B"
$PN"2"37;
"A"
$PN"1"19;
%"Q_RES"
"1","(3550,2100)","0","pure_quanta","I27";
;
LOCATION"R1162"
$SEC"1"
CDS_SEC"1"
VALUE"0"
CDS_LIB"pure_quanta"
WATTAGE"1/16W"
MATERIAL"CHIP"
TOLERANCE"5%"
PART_NUMBER"CS00002JB38"
PACK_TYPE"0402LF";
"B"
$PN"2"39;
"A"
$PN"1"34;
%"Q_RES"
"1","(3550,2150)","0","pure_quanta","I28";
;
LOCATION"R1161"
$SEC"1"
CDS_SEC"1"
VALUE"0"
CDS_LIB"pure_quanta"
WATTAGE"1/16W"
MATERIAL"CHIP"
TOLERANCE"5%"
PART_NUMBER"CS00002JB38"
PACK_TYPE"0402LF";
"B"
$PN"2"40;
"A"
$PN"1"33;
%"UNIVERSAL_GND"
"1","(2500,1850)","0","pure_quanta_power","I29";
;
CDS_LIB"pure_quanta_power"
HDL_POWER"GND";
"A"3;
%"Q_RES"
"1","(2075,3625)","0","pure_quanta","I30";
;
LOCATION"R146"
$SEC"1"
CDS_SEC"1"
MATERIAL"EMPTY"
VALUE"0"
CDS_LIB"pure_quanta"
WATTAGE"1/16W"
TOLERANCE"5%"
PART_NUMBER"CS00002JB38"
PACK_TYPE"0402LF";
"B"
$PN"2"24;
"A"
$PN"1"22;
%"Q_RES"
"1","(2075,3550)","0","pure_quanta","I31";
;
LOCATION"R147"
$SEC"1"
CDS_SEC"1"
MATERIAL"EMPTY"
VALUE"0"
CDS_LIB"pure_quanta"
WATTAGE"1/16W"
TOLERANCE"5%"
PART_NUMBER"CS00002JB38"
PACK_TYPE"0402LF";
"B"
$PN"2"23;
"A"
$PN"1"30;
%"Q_RES"
"1","(2025,3200)","0","pure_quanta","I32";
;
LOCATION"R145"
$SEC"1"
CDS_SEC"1"
MATERIAL"EMPTY"
VALUE"0"
CDS_LIB"pure_quanta"
WATTAGE"1/16W"
TOLERANCE"5%"
PART_NUMBER"CS00002JB38"
PACK_TYPE"0402LF";
"B"
$PN"2"19;
"A"
$PN"1"20;
%"Q_RES"
"1","(2025,3275)","0","pure_quanta","I33";
;
LOCATION"R144"
$SEC"1"
CDS_SEC"1"
MATERIAL"EMPTY"
VALUE"0"
CDS_LIB"pure_quanta"
WATTAGE"1/16W"
TOLERANCE"5%"
PART_NUMBER"CS00002JB38"
PACK_TYPE"0402LF";
"B"
$PN"2"36;
"A"
$PN"1"21;
%"P1V0"
"1","(1250,2975)","0","pure_quanta_power","I34";
;
HDL_POWER"PVDD18_S5_P0"
CDS_LIB"pure_quanta_power";
"A"27;
%"IML3112Y2B000NCG8"
"1","(2050,2200)","0","pure_quanta","I35";
;
LOCATION"U6"
$SEC"1"
CDS_SEC"1"
PART_TYPE"SMLF"
MATERIAL"IC"
PART_NUMBER"AL003112004"
VALUE"IML3112-Y2B000NCG8"
CDS_LIB"pure_quanta"
NEEDS_NO_SIZE"TRUE"
CDS_LMAN_SYM_OUTLINE"-275,250,275,-250";
"TH_GND"
$PN"9"3;
"LSDA_1||HSA"
$PN"8"34;
"HSCL"
$PN"3"21;
"LSCL_0"
$PN"4"36;
"LSDA_0"
$PN"1"19;
"VIO"
$PN"7"25;
"LSCL_1"
$PN"6"33;
"VDD"
$PN"5"27;
"HSDA"
$PN"2"20;
%"Q_CAP"
"1","(1075,2625)","0","pure_quanta","I36";
;
LOCATION"C25"
$SEC"1"
CDS_SEC"1"
MATERIAL"X6S"
TOLERANCE"20%"
VALUE"10UF"
VOLTAGE"6.3V"
PACK_TYPE"C0402"
CDS_LIB"pure_quanta"
PART_NUMBER"CH6101MEB01";
"B"
$PN"2"4;
"A"
$PN"1"27;
%"UNIVERSAL_GND"
"1","(1075,2425)","0","pure_quanta_power","I37";
;
CDS_LIB"pure_quanta_power"
HDL_POWER"GND";
"A"4;
%"Q_RES"
"1","(800,2800)","0","pure_quanta","I38";
;
LOCATION"R140"
$SEC"1"
CDS_SEC"1"
MATERIAL"EMPTY"
VALUE"0"
CDS_LIB"pure_quanta"
WATTAGE"1/16W"
TOLERANCE"5%"
PART_NUMBER"CS00002JB38"
PACK_TYPE"0402LF";
"B"
$PN"2"27;
"A"
$PN"1"25;
%"UNIVERSAL_GND"
"1","(550,2425)","0","pure_quanta_power","I39";
;
CDS_LIB"pure_quanta_power"
HDL_POWER"GND";
"A"5;
%"Q_CAP"
"1","(550,2625)","0","pure_quanta","I40";
;
LOCATION"C22"
$SEC"1"
CDS_SEC"1"
PACK_TYPE"C0402"
MATERIAL"X6S"
TOLERANCE"10%"
VALUE"1UF"
VOLTAGE"25V"
CDS_LIB"pure_quanta"
PART_NUMBER"CH5104KEB02";
"B"
$PN"2"5;
"A"
$PN"1"25;
%"Q_RES"
"1","(2100,1500)","0","pure_quanta","I41";
;
LOCATION"R148"
$SEC"1"
CDS_SEC"1"
VALUE"0"
MATERIAL"EMPTY"
CDS_LIB"pure_quanta"
WATTAGE"1/16W"
TOLERANCE"5%"
PART_NUMBER"CS00002JB38"
PACK_TYPE"0402LF";
"B"
$PN"2"33;
"A"
$PN"1"21;
%"Q_RES"
"1","(2100,1425)","0","pure_quanta","I42";
;
LOCATION"R358"
$SEC"1"
CDS_SEC"1"
MATERIAL"EMPTY"
VALUE"0"
CDS_LIB"pure_quanta"
WATTAGE"1/16W"
TOLERANCE"5%"
PART_NUMBER"CS00002JB38"
PACK_TYPE"0402LF";
"B"
$PN"2"34;
"A"
$PN"1"20;
%"Q_RES"
"2","(7250,4050)","0","pure_quanta","I46";
;
LOCATION"R370"
$SEC"1"
CDS_SEC"1"
PACK_TYPE"0402LF"
WATTAGE"1/16W"
MATERIAL"CHIP"
TOLERANCE"1%"
VALUE"1K"
CDS_LIB"pure_quanta"
PART_NUMBER"TMP_QCS21002FB24";
"A"
$PN"1"28;
"B"
$PN"2"17;
%"Q_RES"
"2","(6925,4050)","0","pure_quanta","I48";
;
LOCATION"R367"
$SEC"1"
CDS_SEC"1"
PACK_TYPE"0402LF"
WATTAGE"1/16W"
MATERIAL"CHIP"
TOLERANCE"1%"
VALUE"1K"
CDS_LIB"pure_quanta"
PART_NUMBER"TMP_QCS21002FB24";
"A"
$PN"1"28;
"B"
$PN"2"16;
%"Q_RES"
"1","(3525,4425)","0","pure_quanta","I5";
;
LOCATION"R1155"
$SEC"1"
CDS_SEC"1"
VALUE"0"
CDS_LIB"pure_quanta"
WATTAGE"1/16W"
MATERIAL"CHIP"
TOLERANCE"5%"
PART_NUMBER"CS00002JB38"
PACK_TYPE"0402LF";
"B"
$PN"2"38;
"A"
$PN"1"9;
%"Q_RES"
"2","(6625,4050)","0","pure_quanta","I50";
;
LOCATION"R363"
$SEC"1"
CDS_SEC"1"
WATTAGE"1/16W"
PACK_TYPE"0402LF"
MATERIAL"CHIP"
TOLERANCE"1%"
VALUE"1K"
CDS_LIB"pure_quanta"
PART_NUMBER"TMP_QCS21002FB24";
"A"
$PN"1"28;
"B"
$PN"2"15;
%"Q_RES"
"2","(6300,4050)","0","pure_quanta","I52";
;
LOCATION"R360"
$SEC"1"
CDS_SEC"1"
PACK_TYPE"0402LF"
WATTAGE"1/16W"
MATERIAL"CHIP"
TOLERANCE"1%"
VALUE"1K"
CDS_LIB"pure_quanta"
PART_NUMBER"TMP_QCS21002FB24";
"A"
$PN"1"28;
"B"
$PN"2"42;
%"Q_RES"
"2","(7225,3125)","0","pure_quanta","I54";
;
LOCATION"R369"
$SEC"1"
CDS_SEC"1"
PACK_TYPE"0402LF"
MATERIAL"CHIP"
WATTAGE"1/16W"
VALUE"1K"
TOLERANCE"1%"
CDS_LIB"pure_quanta"
PART_NUMBER"TMP_QCS21002FB24";
"A"
$PN"1"18;
"B"
$PN"2"14;
%"Q_RES"
"2","(6900,3125)","0","pure_quanta","I56";
;
LOCATION"R366"
$SEC"1"
CDS_SEC"1"
MATERIAL"CHIP"
PACK_TYPE"0402LF"
WATTAGE"1/16W"
TOLERANCE"1%"
VALUE"1K"
CDS_LIB"pure_quanta"
PART_NUMBER"TMP_QCS21002FB24";
"A"
$PN"1"18;
"B"
$PN"2"13;
%"Q_RES"
"2","(6600,3125)","0","pure_quanta","I58";
;
LOCATION"R362"
$SEC"1"
CDS_SEC"1"
WATTAGE"1/16W"
PACK_TYPE"0402LF"
MATERIAL"CHIP"
TOLERANCE"1%"
VALUE"1K"
CDS_LIB"pure_quanta"
PART_NUMBER"TMP_QCS21002FB24";
"A"
$PN"1"18;
"B"
$PN"2"12;
%"Q_RES"
"1","(3525,4375)","0","pure_quanta","I6";
;
LOCATION"R1156"
$SEC"1"
CDS_SEC"1"
VALUE"0"
CDS_LIB"pure_quanta"
WATTAGE"1/16W"
MATERIAL"CHIP"
TOLERANCE"5%"
PART_NUMBER"CS00002JB38"
PACK_TYPE"0402LF";
"B"
$PN"2"10;
"A"
$PN"1"32;
%"Q_RES"
"2","(6275,3125)","0","pure_quanta","I60";
;
LOCATION"R359"
$SEC"1"
CDS_SEC"1"
WATTAGE"1/16W"
PACK_TYPE"0402LF"
MATERIAL"CHIP"
TOLERANCE"1%"
VALUE"1K"
CDS_LIB"pure_quanta"
PART_NUMBER"TMP_QCS21002FB24";
"A"
$PN"1"18;
"B"
$PN"2"29;
%"VCC_CORE"
"1","(7250,4400)","0","pure_quanta_power","I63";
;
HDL_POWER"PVDD11_S3_P0"
CDS_LIB"pure_quanta_power";
"A"28;
%"VCC_CORE"
"1","(7225,3475)","0","pure_quanta_power","I64";
;
HDL_POWER"PVDD11_S3_P1"
CDS_LIB"pure_quanta_power";
"A"18;
%"Q_RES"
"1","(3525,4275)","0","pure_quanta","I7";
;
LOCATION"R1157"
$SEC"1"
CDS_SEC"1"
VALUE"0"
CDS_LIB"pure_quanta"
WATTAGE"1/16W"
MATERIAL"CHIP"
TOLERANCE"5%"
PART_NUMBER"CS00002JB38"
PACK_TYPE"0402LF";
"B"
$PN"2"41;
"A"
$PN"1"24;
%"Q_RES"
"2","(3375,4000)","0","pure_quanta","I73";
;
LOCATION"R5004"
$SEC"1"
CDS_SEC"1"
PACK_TYPE"0402LF"
MATERIAL"CHIP"
TOLERANCE"1%"
WATTAGE"1/16W"
VALUE"10K"
CDS_LIB"pure_quanta"
PART_NUMBER"CS31002FB08";
"A"
$PN"1"23;
"B"
$PN"2"6;
%"UNIVERSAL_GND"
"1","(3375,3750)","0","pure_quanta_power","I74";
;
HDL_POWER"GND"
CDS_LIB"pure_quanta_power";
"A"6;
%"Q_RES"
"2","(3375,1875)","0","pure_quanta","I75";
;
LOCATION"R5005"
$SEC"1"
CDS_SEC"1"
TOLERANCE"1%"
PACK_TYPE"0402LF"
VALUE"10K"
MATERIAL"CHIP"
WATTAGE"1/16W"
CDS_LIB"pure_quanta"
PART_NUMBER"CS31002FB08";
"A"
$PN"1"34;
"B"
$PN"2"7;
%"UNIVERSAL_GND"
"1","(3375,1625)","0","pure_quanta_power","I76";
;
HDL_POWER"GND"
CDS_LIB"pure_quanta_power";
"A"7;
%"Q_RES"
"1","(3525,4225)","0","pure_quanta","I8";
;
LOCATION"R1158"
$SEC"1"
CDS_SEC"1"
VALUE"0"
CDS_LIB"pure_quanta"
WATTAGE"1/16W"
MATERIAL"CHIP"
TOLERANCE"5%"
PART_NUMBER"CS00002JB38"
PACK_TYPE"0402LF";
"B"
$PN"2"11;
"A"
$PN"1"23;
%"UNIVERSAL_GND"
"1","(2500,3975)","0","pure_quanta_power","I9";
;
CDS_LIB"pure_quanta_power"
HDL_POWER"GND";
"A"8;
END.
